(kicad_pcb
	(version 20241229)
	(generator "pcbnew")
	(generator_version "9.0")
	(general
		(thickness 1.599998)
		(legacy_teardrops no)
	)
	(paper "A4")
	(title_block
		(date "2023-02-12")
		(rev "1.1.5")
		(comment 9 "footprint 108 of 473 (U3), pads 312-391 of 484")
	)
	(layers
		(0 "F.Cu" signal)
		(4 "In1.Cu" power "In1.GND")
		(6 "In2.Cu" signal)
		(8 "In3.Cu" power "In3.GND")
		(10 "In4.Cu" power "In4.VCC")
		(12 "In5.Cu" signal)
		(14 "In6.Cu" power "In6.VCC")
		(2 "B.Cu" signal)
		(9 "F.Adhes" user "F.Adhesive")
		(11 "B.Adhes" user "B.Adhesive")
		(13 "F.Paste" user)
		(15 "B.Paste" user)
		(5 "F.SilkS" user "F.Silkscreen")
		(7 "B.SilkS" user "B.Silkscreen")
		(1 "F.Mask" user)
		(3 "B.Mask" user)
		(17 "Dwgs.User" user "User.Drawings")
		(19 "Cmts.User" user "User.Comments")
		(21 "Eco1.User" user "User.Eco1")
		(23 "Eco2.User" user "User.Eco2")
		(25 "Edge.Cuts" user)
		(27 "Margin" user)
		(31 "F.CrtYd" user "F.Courtyard")
		(29 "B.CrtYd" user "B.Courtyard")
		(35 "F.Fab" user)
		(33 "B.Fab" user)
	)
	(footprint "antmicro-footprints:BGA-484_23x23mm_Layout22x22_P1mm_FBG484"
		(locked yes)
		(layer "F.Cu")
		(at 169.036328 95.997157 -90)
		(property "Reference" "U3"
			(at -11.8 -12 270)
			(layer "F.SilkS")
			(effects
				(font
					(size 0.7 0.7)
					(thickness 0.15)
				)
				(justify left bottom)
			)
		)
		(property "Value" "XC7K70T-FBG484"
			(at -10.4 0.4 270)
			(layer "F.Fab")
			(effects
				(font
					(size 0.7 0.7)
					(thickness 0.15)
				)
				(justify left bottom)
			)
		)
		(property "Description" "Kintex®-7 Field Programmable Gate Array (FPGA) IC 285 484-BBGA, FCBGA"
			(at 0 0 270)
			(layer "F.Fab")
			(hide yes)
			(effects
				(font
					(size 1.27 1.27)
					(thickness 0.15)
				)
			)
		)
		(property "Author" "Antmicro"
			(at 73.039171 265.033485 0)
			(layer "F.Fab")
			(hide yes)
			(effects
				(font
					(size 1 1)
					(thickness 0.15)
				)
			)
		)
		(property "License" "Apache-2.0"
			(at 73.039171 265.033485 0)
			(layer "F.Fab")
			(hide yes)
			(effects
				(font
					(size 1 1)
					(thickness 0.15)
				)
			)
		)
		(property "MPN" "XC7K70T-1FBG484C"
			(at 73.039171 265.033485 0)
			(layer "F.Fab")
			(hide yes)
			(effects
				(font
					(size 1 1)
					(thickness 0.15)
				)
			)
		)
		(property "Manufacturer" "AMD-Xilinx"
			(at 73.039171 265.033485 0)
			(layer "F.Fab")
			(hide yes)
			(effects
				(font
					(size 1 1)
					(thickness 0.15)
				)
			)
		)
		(sheetname "FPGA Banks")
		(sheetfile "fpga-banks.kicad_sch")
		(attr smd)
		(pad "N4" smd circle
			(at -7.5 1.5 270)
			(size 0.51 0.51)
			(layers "F.Cu" "F.Mask" "F.Paste")
			(net 396 "CKE0_A")
			(pinfunction "IO_L9N_T1_DQS_34")
			(pintype "bidirectional")
		)
		(pad "N5" smd circle
			(at -6.5 1.5 270)
			(size 0.51 0.51)
			(layers "F.Cu" "F.Mask" "F.Paste")
			(net 406 "IO_N5")
			(pinfunction "IO_L18P_T2_34")
			(pintype "bidirectional")
		)
		(pad "N6" smd circle
			(at -5.5 1.5 270)
			(size 0.51 0.51)
			(layers "F.Cu" "F.Mask" "F.Paste")
			(net 5 "GND")
			(pinfunction "GND")
			(pintype "passive")
		)
		(pad "N7" smd circle
			(at -4.5 1.5 270)
			(size 0.51 0.51)
			(layers "F.Cu" "F.Mask" "F.Paste")
			(net 459 "3V3_SYS")
			(pinfunction "VCCO_0")
			(pintype "passive")
		)
		(pad "N8" smd circle
			(at -3.5 1.5 270)
			(size 0.51 0.51)
			(layers "F.Cu" "F.Mask" "F.Paste")
			(net 5 "GND")
			(pinfunction "GND")
			(pintype "passive")
		)
		(pad "N9" smd circle
			(at -2.5 1.5 270)
			(size 0.51 0.51)
			(layers "F.Cu" "F.Mask" "F.Paste")
			(net 465 "1V0_SYS")
			(pinfunction "VCCINT")
			(pintype "passive")
		)
		(pad "N10" smd circle
			(at -1.5 1.5 270)
			(size 0.51 0.51)
			(layers "F.Cu" "F.Mask" "F.Paste")
			(net 5 "GND")
			(pinfunction "GND")
			(pintype "passive")
		)
		(pad "N11" smd circle
			(at -0.5 1.5 270)
			(size 0.51 0.51)
			(layers "F.Cu" "F.Mask" "F.Paste")
			(net 5 "GND")
			(pinfunction "DXN_0")
			(pintype "bidirectional")
		)
		(pad "N12" smd circle
			(at 0.5 1.5 270)
			(size 0.51 0.51)
			(layers "F.Cu" "F.Mask" "F.Paste")
			(net 5 "GND")
			(pinfunction "DXP_0")
			(pintype "bidirectional")
		)
		(pad "N13" smd circle
			(at 1.5 1.5 270)
			(size 0.51 0.51)
			(layers "F.Cu" "F.Mask" "F.Paste")
			(net 465 "1V0_SYS")
			(pinfunction "VCCBRAM")
			(pintype "passive")
		)
		(pad "N14" smd circle
			(at 2.5 1.5 270)
			(size 0.51 0.51)
			(layers "F.Cu" "F.Mask" "F.Paste")
			(net 5 "GND")
			(pinfunction "GND")
			(pintype "passive")
		)
		(pad "N15" smd circle
			(at 3.5 1.5 270)
			(size 0.51 0.51)
			(layers "F.Cu" "F.Mask" "F.Paste")
			(net 465 "1V0_SYS")
			(pinfunction "VCCINT")
			(pintype "passive")
		)
		(pad "N16" smd circle
			(at 4.5 1.5 270)
			(size 0.51 0.51)
			(layers "F.Cu" "F.Mask" "F.Paste")
			(net 5 "GND")
			(pinfunction "GND")
			(pintype "passive")
		)
		(pad "N17" smd circle
			(at 5.5 1.5 270)
			(size 0.51 0.51)
			(layers "F.Cu" "F.Mask" "F.Paste")
			(net 422 "unconnected-(U3H-IO_L23N_T3_A02_D18_14-PadN17)")
			(pinfunction "IO_L23N_T3_A02_D18_14")
			(pintype "bidirectional+no_connect")
		)
		(pad "N18" smd circle
			(at 6.5 1.5 270)
			(size 0.51 0.51)
			(layers "F.Cu" "F.Mask" "F.Paste")
			(net 423 "unconnected-(U3H-IO_L13P_T2_MRCC_14-PadN18)")
			(pinfunction "IO_L13P_T2_MRCC_14")
			(pintype "bidirectional+no_connect")
		)
		(pad "N19" smd circle
			(at 7.5 1.5 270)
			(size 0.51 0.51)
			(layers "F.Cu" "F.Mask" "F.Paste")
			(net 424 "unconnected-(U3H-IO_L13N_T2_MRCC_14-PadN19)")
			(pinfunction "IO_L13N_T2_MRCC_14")
			(pintype "bidirectional+no_connect")
		)
		(pad "N20" smd circle
			(at 8.5 1.5 270)
			(size 0.51 0.51)
			(layers "F.Cu" "F.Mask" "F.Paste")
			(net 425 "unconnected-(U3H-IO_L17P_T2_A14_D30_14-PadN20)")
			(pinfunction "IO_L17P_T2_A14_D30_14")
			(pintype "bidirectional+no_connect")
		)
		(pad "N21" smd circle
			(at 9.5 1.5 270)
			(size 0.51 0.51)
			(layers "F.Cu" "F.Mask" "F.Paste")
			(net 459 "3V3_SYS")
			(pinfunction "VCCO_14")
			(pintype "passive")
		)
		(pad "N22" smd circle
			(at 10.5 1.5 270)
			(size 0.51 0.51)
			(layers "F.Cu" "F.Mask" "F.Paste")
			(net 426 "unconnected-(U3H-IO_L15P_T2_DQS_RDWR_B_14-PadN22)")
			(pinfunction "IO_L15P_T2_DQS_RDWR_B_14")
			(pintype "bidirectional+no_connect")
		)
		(pad "P1" smd circle
			(at -10.5 2.5 270)
			(size 0.51 0.51)
			(layers "F.Cu" "F.Mask" "F.Paste")
			(net 345 "DQ06_A")
			(pinfunction "IO_L8P_T1_34")
			(pintype "bidirectional")
		)
		(pad "P2" smd circle
			(at -9.5 2.5 270)
			(size 0.51 0.51)
			(layers "F.Cu" "F.Mask" "F.Paste")
			(net 344 "DQ05_A")
			(pinfunction "IO_L7P_T1_34")
			(pintype "bidirectional")
		)
		(pad "P3" smd circle
			(at -8.5 2.5 270)
			(size 0.51 0.51)
			(layers "F.Cu" "F.Mask" "F.Paste")
			(net 5 "GND")
			(pinfunction "GND")
			(pintype "passive")
		)
		(pad "P4" smd circle
			(at -7.5 2.5 270)
			(size 0.51 0.51)
			(layers "F.Cu" "F.Mask" "F.Paste")
			(net 402 "IO_P4")
			(pinfunction "IO_L11P_T1_SRCC_34")
			(pintype "bidirectional")
		)
		(pad "P5" smd circle
			(at -6.5 2.5 270)
			(size 0.51 0.51)
			(layers "F.Cu" "F.Mask" "F.Paste")
			(net 427 "unconnected-(U3D-IO_L18N_T2_34-PadP5)")
			(pinfunction "IO_L18N_T2_34")
			(pintype "bidirectional+no_connect")
		)
		(pad "P6" smd circle
			(at -5.5 2.5 270)
			(size 0.51 0.51)
			(layers "F.Cu" "F.Mask" "F.Paste")
			(net 21 "DONE")
			(pinfunction "DONE_0")
			(pintype "bidirectional")
		)
		(pad "P7" smd circle
			(at -4.5 2.5 270)
			(size 0.51 0.51)
			(layers "F.Cu" "F.Mask" "F.Paste")
			(net 460 "1V8_SYS")
			(pinfunction "VCCBATT_0")
			(pintype "power_in")
		)
		(pad "P8" smd circle
			(at -3.5 2.5 270)
			(size 0.51 0.51)
			(layers "F.Cu" "F.Mask" "F.Paste")
			(net 460 "1V8_SYS")
			(pinfunction "VCCAUX")
			(pintype "passive")
		)
		(pad "P9" smd circle
			(at -2.5 2.5 270)
			(size 0.51 0.51)
			(layers "F.Cu" "F.Mask" "F.Paste")
			(net 5 "GND")
			(pinfunction "GND")
			(pintype "passive")
		)
		(pad "P10" smd circle
			(at -1.5 2.5 270)
			(size 0.51 0.51)
			(layers "F.Cu" "F.Mask" "F.Paste")
			(net 460 "1V8_SYS")
			(pinfunction "VCCAUX")
			(pintype "passive")
		)
		(pad "P11" smd circle
			(at -0.5 2.5 270)
			(size 0.51 0.51)
			(layers "F.Cu" "F.Mask" "F.Paste")
			(net 5 "GND")
			(pinfunction "GND")
			(pintype "passive")
		)
		(pad "P12" smd circle
			(at 0.5 2.5 270)
			(size 0.51 0.51)
			(layers "F.Cu" "F.Mask" "F.Paste")
			(net 460 "1V8_SYS")
			(pinfunction "VCCAUX")
			(pintype "passive")
		)
		(pad "P13" smd circle
			(at 1.5 2.5 270)
			(size 0.51 0.51)
			(layers "F.Cu" "F.Mask" "F.Paste")
			(net 5 "GND")
			(pinfunction "GND")
			(pintype "passive")
		)
		(pad "P14" smd circle
			(at 2.5 2.5 270)
			(size 0.51 0.51)
			(layers "F.Cu" "F.Mask" "F.Paste")
			(net 465 "1V0_SYS")
			(pinfunction "VCCINT")
			(pintype "passive")
		)
		(pad "P15" smd circle
			(at 3.5 2.5 270)
			(size 0.51 0.51)
			(layers "F.Cu" "F.Mask" "F.Paste")
			(net 5 "GND")
			(pinfunction "GND")
			(pintype "passive")
		)
		(pad "P16" smd circle
			(at 4.5 2.5 270)
			(size 0.51 0.51)
			(layers "F.Cu" "F.Mask" "F.Paste")
			(net 428 "unconnected-(U3H-IO_L23P_T3_A03_D19_14-PadP16)")
			(pinfunction "IO_L23P_T3_A03_D19_14")
			(pintype "bidirectional+no_connect")
		)
		(pad "P17" smd circle
			(at 5.5 2.5 270)
			(size 0.51 0.51)
			(layers "F.Cu" "F.Mask" "F.Paste")
			(net 429 "unconnected-(U3H-IO_L21N_T3_DQS_A06_D22_14-PadP17)")
			(pinfunction "IO_L21N_T3_DQS_A06_D22_14")
			(pintype "bidirectional+no_connect")
		)
		(pad "P18" smd circle
			(at 6.5 2.5 270)
			(size 0.51 0.51)
			(layers "F.Cu" "F.Mask" "F.Paste")
			(net 459 "3V3_SYS")
			(pinfunction "VCCO_14")
			(pintype "passive")
		)
		(pad "P19" smd circle
			(at 7.5 2.5 270)
			(size 0.51 0.51)
			(layers "F.Cu" "F.Mask" "F.Paste")
			(net 430 "unconnected-(U3H-IO_L20P_T3_A08_D24_14-PadP19)")
			(pinfunction "IO_L20P_T3_A08_D24_14")
			(pintype "bidirectional+no_connect")
		)
		(pad "P20" smd circle
			(at 8.5 2.5 270)
			(size 0.51 0.51)
			(layers "F.Cu" "F.Mask" "F.Paste")
			(net 431 "unconnected-(U3H-IO_L20N_T3_A07_D23_14-PadP20)")
			(pinfunction "IO_L20N_T3_A07_D23_14")
			(pintype "bidirectional+no_connect")
		)
		(pad "P21" smd circle
			(at 9.5 2.5 270)
			(size 0.51 0.51)
			(layers "F.Cu" "F.Mask" "F.Paste")
			(net 46 "TMDS_D0_P")
			(pinfunction "IO_L22P_T3_A05_D21_14")
			(pintype "bidirectional")
		)
		(pad "P22" smd circle
			(at 10.5 2.5 270)
			(size 0.51 0.51)
			(layers "F.Cu" "F.Mask" "F.Paste")
			(net 47 "TMDS_D0_N")
			(pinfunction "IO_L22N_T3_A04_D20_14")
			(pintype "bidirectional")
		)
		(pad "R1" smd circle
			(at -10.5 3.5 270)
			(size 0.51 0.51)
			(layers "F.Cu" "F.Mask" "F.Paste")
			(net 343 "DQ04_A")
			(pinfunction "IO_L8N_T1_34")
			(pintype "bidirectional")
		)
		(pad "R2" smd circle
			(at -9.5 3.5 270)
			(size 0.51 0.51)
			(layers "F.Cu" "F.Mask" "F.Paste")
			(net 341 "DQ12_A")
			(pinfunction "IO_L7N_T1_34")
			(pintype "bidirectional")
		)
		(pad "R3" smd circle
			(at -8.5 3.5 270)
			(size 0.51 0.51)
			(layers "F.Cu" "F.Mask" "F.Paste")
			(net 432 "unconnected-(U3D-IO_L12P_T1_MRCC_34-PadR3)")
			(pinfunction "IO_L12P_T1_MRCC_34")
			(pintype "bidirectional+no_connect")
		)
		(pad "R4" smd circle
			(at -7.5 3.5 270)
			(size 0.51 0.51)
			(layers "F.Cu" "F.Mask" "F.Paste")
			(net 401 "IO_R4")
			(pinfunction "IO_L11N_T1_SRCC_34")
			(pintype "bidirectional")
		)
		(pad "R5" smd circle
			(at -6.5 3.5 270)
			(size 0.51 0.51)
			(layers "F.Cu" "F.Mask" "F.Paste")
			(net 66 "VDDQ")
			(pinfunction "VCCO_34")
			(pintype "passive")
		)
		(pad "R6" smd circle
			(at -5.5 3.5 270)
			(size 0.51 0.51)
			(layers "F.Cu" "F.Mask" "F.Paste")
			(net 433 "unconnected-(U3E-IO_L8N_T1_33-PadR6)")
			(pinfunction "IO_L8N_T1_33")
			(pintype "bidirectional+no_connect")
		)
		(pad "R7" smd circle
			(at -4.5 3.5 270)
			(size 0.51 0.51)
			(layers "F.Cu" "F.Mask" "F.Paste")
			(net 434 "unconnected-(U3E-IO_L8P_T1_33-PadR7)")
			(pinfunction "IO_L8P_T1_33")
			(pintype "bidirectional+no_connect")
		)
		(pad "R8" smd circle
			(at -3.5 3.5 270)
			(size 0.51 0.51)
			(layers "F.Cu" "F.Mask" "F.Paste")
			(net 5 "GND")
			(pinfunction "GND")
			(pintype "passive")
		)
		(pad "R9" smd circle
			(at -2.5 3.5 270)
			(size 0.51 0.51)
			(layers "F.Cu" "F.Mask" "F.Paste")
			(net 460 "1V8_SYS")
			(pinfunction "VCCAUX")
			(pintype "passive")
		)
		(pad "R10" smd circle
			(at -1.5 3.5 270)
			(size 0.51 0.51)
			(layers "F.Cu" "F.Mask" "F.Paste")
			(net 5 "GND")
			(pinfunction "GND")
			(pintype "passive")
		)
		(pad "R11" smd circle
			(at -0.5 3.5 270)
			(size 0.51 0.51)
			(layers "F.Cu" "F.Mask" "F.Paste")
			(net 460 "1V8_SYS")
			(pinfunction "VCCAUX")
			(pintype "passive")
		)
		(pad "R12" smd circle
			(at 0.5 3.5 270)
			(size 0.51 0.51)
			(layers "F.Cu" "F.Mask" "F.Paste")
			(net 5 "GND")
			(pinfunction "GND")
			(pintype "passive")
		)
		(pad "R13" smd circle
			(at 1.5 3.5 270)
			(size 0.51 0.51)
			(layers "F.Cu" "F.Mask" "F.Paste")
			(net 465 "1V0_SYS")
			(pinfunction "VCCBRAM")
			(pintype "passive")
		)
		(pad "R14" smd circle
			(at 2.5 3.5 270)
			(size 0.51 0.51)
			(layers "F.Cu" "F.Mask" "F.Paste")
			(net 5 "GND")
			(pinfunction "GND")
			(pintype "passive")
		)
		(pad "R15" smd circle
			(at 3.5 3.5 270)
			(size 0.51 0.51)
			(layers "F.Cu" "F.Mask" "F.Paste")
			(net 465 "1V0_SYS")
			(pinfunction "VCCINT")
			(pintype "passive")
		)
		(pad "R16" smd circle
			(at 4.5 3.5 270)
			(size 0.51 0.51)
			(layers "F.Cu" "F.Mask" "F.Paste")
			(net 435 "unconnected-(U3I-IO_L20P_T3_13-PadR16)")
			(pinfunction "IO_L20P_T3_13")
			(pintype "bidirectional+no_connect")
		)
		(pad "R17" smd circle
			(at 5.5 3.5 270)
			(size 0.51 0.51)
			(layers "F.Cu" "F.Mask" "F.Paste")
			(net 437 "unconnected-(U3H-IO_L21P_T3_DQS_14-PadR17)")
			(pinfunction "IO_L21P_T3_DQS_14")
			(pintype "bidirectional+no_connect")
		)
		(pad "R18" smd circle
			(at 6.5 3.5 270)
			(size 0.51 0.51)
			(layers "F.Cu" "F.Mask" "F.Paste")
			(net 438 "unconnected-(U3H-IO_L19P_T3_A10_D26_14-PadR18)")
			(pinfunction "IO_L19P_T3_A10_D26_14")
			(pintype "bidirectional+no_connect")
		)
		(pad "R19" smd circle
			(at 7.5 3.5 270)
			(size 0.51 0.51)
			(layers "F.Cu" "F.Mask" "F.Paste")
			(net 439 "unconnected-(U3H-IO_L19N_T3_A09_D25_VREF_14-PadR19)")
			(pinfunction "IO_L19N_T3_A09_D25_VREF_14")
			(pintype "bidirectional+no_connect")
		)
		(pad "R20" smd circle
			(at 8.5 3.5 270)
			(size 0.51 0.51)
			(layers "F.Cu" "F.Mask" "F.Paste")
			(net 5 "GND")
			(pinfunction "GND")
			(pintype "passive")
		)
		(pad "R21" smd circle
			(at 9.5 3.5 270)
			(size 0.51 0.51)
			(layers "F.Cu" "F.Mask" "F.Paste")
			(net 44 "TMDS_CLK_P")
			(pinfunction "IO_L24P_T3_A01_D17_14")
			(pintype "bidirectional")
		)
		(pad "R22" smd circle
			(at 10.5 3.5 270)
			(size 0.51 0.51)
			(layers "F.Cu" "F.Mask" "F.Paste")
			(net 45 "TMDS_CLK_N")
			(pinfunction "IO_L24N_T3_A00_D16_14")
			(pintype "bidirectional")
		)
		(pad "T1" smd circle
			(at -10.5 4.5 270)
			(size 0.51 0.51)
			(layers "F.Cu" "F.Mask" "F.Paste")
			(net 340 "DQ13_A")
			(pinfunction "IO_L10P_T1_34")
			(pintype "bidirectional")
		)
		(pad "T2" smd circle
			(at -9.5 4.5 270)
			(size 0.51 0.51)
			(layers "F.Cu" "F.Mask" "F.Paste")
			(net 66 "VDDQ")
			(pinfunction "VCCO_34")
			(pintype "passive")
		)
		(pad "T3" smd circle
			(at -8.5 4.5 270)
			(size 0.51 0.51)
			(layers "F.Cu" "F.Mask" "F.Paste")
			(net 339 "DQ14_A")
			(pinfunction "IO_L12N_T1_MRCC_34")
			(pintype "bidirectional")
		)
		(pad "T4" smd circle
			(at -7.5 4.5 270)
			(size 0.51 0.51)
			(layers "F.Cu" "F.Mask" "F.Paste")
			(net 400 "IO_T4")
			(pinfunction "IO_L13P_T2_MRCC_34")
			(pintype "bidirectional")
		)
		(pad "T5" smd circle
			(at -6.5 4.5 270)
			(size 0.51 0.51)
			(layers "F.Cu" "F.Mask" "F.Paste")
			(net 440 "unconnected-(U3D-IO_L16P_T2_34-PadT5)")
			(pinfunction "IO_L16P_T2_34")
			(pintype "bidirectional+no_connect")
		)
		(pad "T6" smd circle
			(at -5.5 4.5 270)
			(size 0.51 0.51)
			(layers "F.Cu" "F.Mask" "F.Paste")
			(net 441 "unconnected-(U3E-IO_0_VRN_33-PadT6)")
			(pinfunction "IO_0_VRN_33")
			(pintype "bidirectional+no_connect")
		)
		(pad "T7" smd circle
			(at -4.5 4.5 270)
			(size 0.51 0.51)
			(layers "F.Cu" "F.Mask" "F.Paste")
			(net 5 "GND")
			(pinfunction "GND")
			(pintype "passive")
		)
		(pad "T8" smd circle
			(at -3.5 4.5 270)
			(size 0.51 0.51)
			(layers "F.Cu" "F.Mask" "F.Paste")
			(net 443 "unconnected-(U3E-IO_L18N_T2_33-PadT8)")
			(pinfunction "IO_L18N_T2_33")
			(pintype "bidirectional+no_connect")
		)
		(pad "T9" smd circle
			(at -2.5 4.5 270)
			(size 0.51 0.51)
			(layers "F.Cu" "F.Mask" "F.Paste")
			(net 445 "unconnected-(U3E-IO_L18P_T2_33-PadT9)")
			(pinfunction "IO_L18P_T2_33")
			(pintype "bidirectional+no_connect")
		)
		(pad "T10" smd circle
			(at -1.5 4.5 270)
			(size 0.51 0.51)
			(layers "F.Cu" "F.Mask" "F.Paste")
			(net 446 "unconnected-(U3E-IO_L16N_T2_33-PadT10)")
			(pinfunction "IO_L16N_T2_33")
			(pintype "bidirectional+no_connect")
		)
		(pad "T11" smd circle
			(at -0.5 4.5 270)
			(size 0.51 0.51)
			(layers "F.Cu" "F.Mask" "F.Paste")
			(net 448 "unconnected-(U3E-IO_L16P_T2_33-PadT11)")
			(pinfunction "IO_L16P_T2_33")
			(pintype "bidirectional+no_connect")
		)
		(pad "T12" smd circle
			(at 0.5 4.5 270)
			(size 0.51 0.51)
			(layers "F.Cu" "F.Mask" "F.Paste")
			(net 66 "VDDQ")
			(pinfunction "VCCO_33")
			(pintype "passive")
		)
		(pad "T13" smd circle
			(at 1.5 4.5 270)
			(size 0.51 0.51)
			(layers "F.Cu" "F.Mask" "F.Paste")
			(net 450 "unconnected-(U3E-IO_L24P_T3_33-PadT13)")
			(pinfunction "IO_L24P_T3_33")
			(pintype "bidirectional+no_connect")
		)
		(pad "T14" smd circle
			(at 2.5 4.5 270)
			(size 0.51 0.51)
			(layers "F.Cu" "F.Mask" "F.Paste")
			(net 452 "unconnected-(U3E-IO_25_VRP_33-PadT14)")
			(pinfunction "IO_25_VRP_33")
			(pintype "bidirectional+no_connect")
		)
		(pad "T15" smd circle
			(at 3.5 4.5 270)
			(size 0.51 0.51)
			(layers "F.Cu" "F.Mask" "F.Paste")
			(net 454 "unconnected-(U3I-IO_L24P_T3_13-PadT15)")
			(pinfunction "IO_L24P_T3_13")
			(pintype "bidirectional+no_connect")
		)
		(pad "T16" smd circle
			(at 4.5 4.5 270)
			(size 0.51 0.51)
			(layers "F.Cu" "F.Mask" "F.Paste")
			(net 456 "unconnected-(U3I-IO_L20N_T3_13-PadT16)")
			(pinfunction "IO_L20N_T3_13")
			(pintype "bidirectional+no_connect")
		)
		(pad "T17" smd circle
			(at 5.5 4.5 270)
			(size 0.51 0.51)
			(layers "F.Cu" "F.Mask" "F.Paste")
			(net 5 "GND")
			(pinfunction "GND")
			(pintype "passive")
		)
	)
)
